# T6G (Grand Teton) — schematic netlist excerpt (pin names and nets, part order shuffled) for the footprints in the layout excerpt that follows; sources: Cadence DE-HDL packaged netlist, KiCad conversion of 04192023_DAF0TMB3IC0_F0TG_MB_C_brd_V02_OCP.brd

R8073  Q_RES  33 5% CHIP  pkg 0402LF  page 200 : A = PVDDCR_CPU1_P0_SMB_ALERT ; B = PVDDCR_CPU1_P0_SMB_ALERT_R
L26  Q_INDUCTOR  BLM15PD121SN1D/1300MA IND  pkg SMLF  page 279 : \1\ = P1V8_CPU0_RT_1D ; \2\ = P1V8_CPU0_RT0_1A_1D

(kicad_pcb
	(version 20260206)
	(generator "pcbnew")
	(generator_version "10.0")
	(general
		(thickness 1.6)
		(legacy_teardrops no)
	)
	(paper "A4")
	(title_block
		(title "04192023_DAF0TMB3IC0_F0TG_MB_C_brd_V02_OCP.brd")
		(comment 1 "Grand Teton / footprints 1824-1825 of 8354")
	)
	(layers
		(0 "F.Cu" signal "TOP")
		(4 "In1.Cu" signal "GND")
		(6 "In2.Cu" signal "IN1")
		(8 "In3.Cu" signal "GND1")
		(10 "In4.Cu" signal "IN2")
		(12 "In5.Cu" signal "GND2")
		(14 "In6.Cu" signal "IN3")
		(16 "In7.Cu" signal "GND3")
		(18 "In8.Cu" signal "VCC")
		(20 "In9.Cu" signal "VCC1")
		(22 "In10.Cu" signal "GND4")
		(24 "In11.Cu" signal "IN4")
		(26 "In12.Cu" signal "GND5")
		(28 "In13.Cu" signal "IN5")
		(30 "In14.Cu" signal "GND6")
		(32 "In15.Cu" signal "IN6")
		(34 "In16.Cu" signal "GND7")
		(2 "B.Cu" signal "BOTTOM")
		(9 "F.Adhes" user "F.Adhesive")
		(11 "B.Adhes" user "B.Adhesive")
		(13 "F.Paste" user "Package Geometry/Pastemask Top")
		(15 "B.Paste" user "Package Geometry/Pastemask Bottom")
		(5 "F.SilkS" user "Ref Des/Silkscreen Top")
		(7 "B.SilkS" user "Ref Des/Silkscreen Bottom")
		(1 "F.Mask" user "Board Geometry/Soldermask Top")
		(3 "B.Mask" user "Board Geometry/Soldermask Bottom")
		(17 "Dwgs.User" user "User.Drawings")
		(19 "Cmts.User" user "User.Comments")
		(21 "Eco1.User" user "User.Eco1")
		(23 "Eco2.User" user "User.Eco2")
		(25 "Edge.Cuts" user "Board Geometry/Outline")
		(27 "Margin" user)
		(31 "F.CrtYd" user "Package Geometry/Place Bound Top")
		(29 "B.CrtYd" user "Package Geometry/Place Bound Bottom")
		(35 "F.Fab" user "Ref Des/Assembly Top")
		(33 "B.Fab" user "Ref Des/Assembly Bottom")
	)
	(footprint ""
		(layer "F.Cu")
		(at 326.662288 -393.47648 180)
		(property "Reference" "L26"
			(at 0 0 180)
			(layer "F.SilkS")
			(hide yes)
			(effects
				(font
					(size 1.27 1.27)
				)
			)
		)
		(property "Value" ""
			(at 0 0 180)
			(layer "F.Fab")
			(effects
				(font
					(size 1.27 1.27)
				)
			)
		)
		(duplicate_pad_numbers_are_jumpers no)
		(fp_line
			(start 0.762 0.381)
			(end -0.762 0.381)
			(stroke
				(width 0.1524)
				(type default)
			)
			(layer "F.SilkS")
		)
		(fp_line
			(start 0.762 -0.381)
			(end 0.762 0.381)
			(stroke
				(width 0.1524)
				(type default)
			)
			(layer "F.SilkS")
		)
		(fp_line
			(start -0.762 0.381)
			(end -0.762 -0.381)
			(stroke
				(width 0.1524)
				(type default)
			)
			(layer "F.SilkS")
		)
		(fp_line
			(start -0.762 -0.381)
			(end 0.762 -0.381)
			(stroke
				(width 0.1524)
				(type default)
			)
			(layer "F.SilkS")
		)
		(fp_line
			(start 0.680466 0.306324)
			(end 0.118364 0.306324)
			(stroke
				(width 0.1)
				(type default)
			)
			(layer "F.Fab")
		)
		(fp_line
			(start 0.680466 -0.306324)
			(end 0.680466 0.306324)
			(stroke
				(width 0.1)
				(type default)
			)
			(layer "F.Fab")
		)
		(fp_line
			(start 0.118872 -0.2794)
			(end 0.118872 -0.306324)
			(stroke
				(width 0.1)
				(type default)
			)
			(layer "F.Fab")
		)
		(fp_line
			(start 0.118872 -0.306324)
			(end 0.680466 -0.306324)
			(stroke
				(width 0.1)
				(type default)
			)
			(layer "F.Fab")
		)
		(fp_line
			(start 0.118364 0.306324)
			(end 0.118364 0.2794)
			(stroke
				(width 0.1)
				(type default)
			)
			(layer "F.Fab")
		)
		(fp_line
			(start 0.118364 0.2794)
			(end -0.119634 0.2794)
			(stroke
				(width 0.1)
				(type default)
			)
			(layer "F.Fab")
		)
		(fp_line
			(start -0.118364 -0.2794)
			(end 0.118872 -0.2794)
			(stroke
				(width 0.1)
				(type default)
			)
			(layer "F.Fab")
		)
		(fp_line
			(start -0.118364 -0.307086)
			(end -0.118364 -0.2794)
			(stroke
				(width 0.1)
				(type default)
			)
			(layer "F.Fab")
		)
		(fp_line
			(start -0.119634 0.30607)
			(end -0.681736 0.30607)
			(stroke
				(width 0.1)
				(type default)
			)
			(layer "F.Fab")
		)
		(fp_line
			(start -0.119634 0.2794)
			(end -0.119634 0.30607)
			(stroke
				(width 0.1)
				(type default)
			)
			(layer "F.Fab")
		)
		(fp_line
			(start -0.681736 0.30607)
			(end -0.681736 -0.307086)
			(stroke
				(width 0.1)
				(type default)
			)
			(layer "F.Fab")
		)
		(fp_line
			(start -0.681736 -0.307086)
			(end -0.118364 -0.307086)
			(stroke
				(width 0.1)
				(type default)
			)
			(layer "F.Fab")
		)
		(pad "1" smd rect
			(at -0.40005 0)
			(size 0.4572 0.508)
			(layers "F.Cu" "F.Mask" "F.Paste")
			(net "P1V8_CPU0_RT_1D")
		)
		(pad "2" smd rect
			(at 0.40005 0)
			(size 0.4572 0.508)
			(layers "F.Cu" "F.Mask" "F.Paste")
			(net "P1V8_CPU0_RT0_1A_1D")
		)
	)
	(footprint ""
		(layer "F.Cu")
		(at 304.419 -365.125)
		(property "Reference" "R8073"
			(at 0 0 0)
			(layer "F.SilkS")
			(hide yes)
			(effects
				(font
					(size 1.27 1.27)
				)
			)
		)
		(property "Value" ""
			(at 0 0 0)
			(layer "F.Fab")
			(effects
				(font
					(size 1.27 1.27)
				)
			)
		)
		(duplicate_pad_numbers_are_jumpers no)
		(fp_line
			(start -0.7874 -0.4064)
			(end 0.7874 -0.4064)
			(stroke
				(width 0.1524)
				(type default)
			)
			(layer "F.SilkS")
		)
		(fp_line
			(start -0.7874 0.4064)
			(end -0.7874 -0.4064)
			(stroke
				(width 0.1524)
				(type default)
			)
			(layer "F.SilkS")
		)
		(fp_line
			(start 0.7874 -0.4064)
			(end 0.7874 0.4064)
			(stroke
				(width 0.1524)
				(type default)
			)
			(layer "F.SilkS")
		)
		(fp_line
			(start 0.7874 0.4064)
			(end -0.7874 0.4064)
			(stroke
				(width 0.1524)
				(type default)
			)
			(layer "F.SilkS")
		)
		(fp_line
			(start -0.67945 -0.305054)
			(end -0.12065 -0.305054)
			(stroke
				(width 0.1)
				(type default)
			)
			(layer "F.Fab")
		)
		(fp_line
			(start -0.67945 0.3048)
			(end -0.67945 -0.305054)
			(stroke
				(width 0.1)
				(type default)
			)
			(layer "F.Fab")
		)
		(fp_line
			(start -0.12065 -0.305054)
			(end -0.12065 -0.2794)
			(stroke
				(width 0.1)
				(type default)
			)
			(layer "F.Fab")
		)
		(fp_line
			(start -0.12065 -0.2794)
			(end 0.12065 -0.2794)
			(stroke
				(width 0.1)
				(type default)
			)
			(layer "F.Fab")
		)
		(fp_line
			(start -0.12065 0.2794)
			(end -0.12065 0.3048)
			(stroke
				(width 0.1)
				(type default)
			)
			(layer "F.Fab")
		)
		(fp_line
			(start -0.12065 0.3048)
			(end -0.67945 0.3048)
			(stroke
				(width 0.1)
				(type default)
			)
			(layer "F.Fab")
		)
		(fp_line
			(start 0.120396 0.2794)
			(end -0.12065 0.2794)
			(stroke
				(width 0.1)
				(type default)
			)
			(layer "F.Fab")
		)
		(fp_line
			(start 0.120396 0.3048)
			(end 0.120396 0.2794)
			(stroke
				(width 0.1)
				(type default)
			)
			(layer "F.Fab")
		)
		(fp_line
			(start 0.12065 -0.3048)
			(end 0.67945 -0.3048)
			(stroke
				(width 0.1)
				(type default)
			)
			(layer "F.Fab")
		)
		(fp_line
			(start 0.12065 -0.2794)
			(end 0.12065 -0.3048)
			(stroke
				(width 0.1)
				(type default)
			)
			(layer "F.Fab")
		)
		(fp_line
			(start 0.67945 -0.3048)
			(end 0.67945 0.3048)
			(stroke
				(width 0.1)
				(type default)
			)
			(layer "F.Fab")
		)
		(fp_line
			(start 0.67945 0.3048)
			(end 0.120396 0.3048)
			(stroke
				(width 0.1)
				(type default)
			)
			(layer "F.Fab")
		)
		(pad "1" smd circle
			(at -0.40005 0)
			(size 0 0)
			(layers "F.Cu" "F.Mask" "F.Paste")
			(net "PVDDCR_CPU1_P0_SMB_ALERT")
		)
		(pad "2" smd circle
			(at 0.40005 0)
			(size 0 0)
			(layers "F.Cu" "F.Mask" "F.Paste")
			(net "PVDDCR_CPU1_P0_SMB_ALERT_R")
		)
	)
)
